# S9S_MB_2U (Grand Teton) — schematic netlist excerpt (pin names and nets, part order shuffled) for the footprints in the layout excerpt that follows; sources: Cadence DE-HDL packaged netlist, KiCad conversion of 03242023_DA0F0TMBIJ0_F0T_Motherboard_J_brd_V01_OCP.brd

C148  Q_CAP_DIFFBUS  DIFF BUS_0.22UF 6.3V 20% X6S  pkg C0201  page 178 : \1\ = DMI_CPU0_PCH_TX_C_DP<3> ; \2\ = DMI_CPU0_PCH_TX_DP<3>
R1012  Q_RES  0 5% CHIP  pkg 0402LF  page 209 : A = CLK_25M_CK440_CPU0_DP ; B = CLK_25M_CK440_CPU0_R_DP

(kicad_pcb
	(version 20260206)
	(generator "pcbnew")
	(generator_version "10.0")
	(general
		(thickness 1.6)
		(legacy_teardrops no)
	)
	(paper "A4")
	(title_block
		(title "03242023_DA0F0TMBIJ0_F0T_Motherboard_J_brd_V01_OCP.brd")
		(comment 1 "Grand Teton / footprints 1225-1226 of 6105")
	)
	(layers
		(0 "F.Cu" signal "TOP")
		(4 "In1.Cu" signal "GND")
		(6 "In2.Cu" signal "IN1")
		(8 "In3.Cu" signal "GND1")
		(10 "In4.Cu" signal "IN2")
		(12 "In5.Cu" signal "GND2")
		(14 "In6.Cu" signal "IN3")
		(16 "In7.Cu" signal "GND3")
		(18 "In8.Cu" signal "VCC")
		(20 "In9.Cu" signal "VCC1")
		(22 "In10.Cu" signal "GND4")
		(24 "In11.Cu" signal "IN4")
		(26 "In12.Cu" signal "GND5")
		(28 "In13.Cu" signal "IN5")
		(30 "In14.Cu" signal "GND6")
		(32 "In15.Cu" signal "IN6")
		(34 "In16.Cu" signal "GND7")
		(2 "B.Cu" signal "BOTTOM")
		(9 "F.Adhes" user "F.Adhesive")
		(11 "B.Adhes" user "B.Adhesive")
		(13 "F.Paste" user "Package Geometry/Pastemask Top")
		(15 "B.Paste" user "Package Geometry/Pastemask Bottom")
		(5 "F.SilkS" user "Ref Des/Silkscreen Top")
		(7 "B.SilkS" user "Ref Des/Silkscreen Bottom")
		(1 "F.Mask" user "Board Geometry/Soldermask Top")
		(3 "B.Mask" user "Board Geometry/Soldermask Bottom")
		(17 "Dwgs.User" user "User.Drawings")
		(19 "Cmts.User" user "User.Comments")
		(21 "Eco1.User" user "User.Eco1")
		(23 "Eco2.User" user "User.Eco2")
		(25 "Edge.Cuts" user "Board Geometry/Outline")
		(27 "Margin" user)
		(31 "F.CrtYd" user "Package Geometry/Place Bound Top")
		(29 "B.CrtYd" user "Package Geometry/Place Bound Bottom")
		(35 "F.Fab" user "Ref Des/Assembly Top")
		(33 "B.Fab" user "Ref Des/Assembly Bottom")
	)
	(footprint ""
		(layer "F.Cu")
		(at 241.314986 -107.771692 180)
		(property "Reference" "R1012"
			(at 0 0 180)
			(layer "F.SilkS")
			(hide yes)
			(effects
				(font
					(size 1.27 1.27)
				)
			)
		)
		(property "Value" ""
			(at 0 0 180)
			(layer "F.Fab")
			(effects
				(font
					(size 1.27 1.27)
				)
			)
		)
		(duplicate_pad_numbers_are_jumpers no)
		(fp_line
			(start 0.7874 0.4064)
			(end -0.7874 0.4064)
			(stroke
				(width 0.1524)
				(type default)
			)
			(layer "F.SilkS")
		)
		(fp_line
			(start 0.7874 -0.4064)
			(end 0.7874 0.4064)
			(stroke
				(width 0.1524)
				(type default)
			)
			(layer "F.SilkS")
		)
		(fp_line
			(start -0.7874 0.4064)
			(end -0.7874 -0.4064)
			(stroke
				(width 0.1524)
				(type default)
			)
			(layer "F.SilkS")
		)
		(fp_line
			(start -0.7874 -0.4064)
			(end 0.7874 -0.4064)
			(stroke
				(width 0.1524)
				(type default)
			)
			(layer "F.SilkS")
		)
		(fp_line
			(start 0.67945 0.3048)
			(end 0.120396 0.3048)
			(stroke
				(width 0.1)
				(type default)
			)
			(layer "F.Fab")
		)
		(fp_line
			(start 0.67945 -0.3048)
			(end 0.67945 0.3048)
			(stroke
				(width 0.1)
				(type default)
			)
			(layer "F.Fab")
		)
		(fp_line
			(start 0.12065 -0.2794)
			(end 0.12065 -0.3048)
			(stroke
				(width 0.1)
				(type default)
			)
			(layer "F.Fab")
		)
		(fp_line
			(start 0.12065 -0.3048)
			(end 0.67945 -0.3048)
			(stroke
				(width 0.1)
				(type default)
			)
			(layer "F.Fab")
		)
		(fp_line
			(start 0.120396 0.3048)
			(end 0.120396 0.2794)
			(stroke
				(width 0.1)
				(type default)
			)
			(layer "F.Fab")
		)
		(fp_line
			(start 0.120396 0.2794)
			(end -0.12065 0.2794)
			(stroke
				(width 0.1)
				(type default)
			)
			(layer "F.Fab")
		)
		(fp_line
			(start -0.12065 0.3048)
			(end -0.67945 0.3048)
			(stroke
				(width 0.1)
				(type default)
			)
			(layer "F.Fab")
		)
		(fp_line
			(start -0.12065 0.2794)
			(end -0.12065 0.3048)
			(stroke
				(width 0.1)
				(type default)
			)
			(layer "F.Fab")
		)
		(fp_line
			(start -0.12065 -0.2794)
			(end 0.12065 -0.2794)
			(stroke
				(width 0.1)
				(type default)
			)
			(layer "F.Fab")
		)
		(fp_line
			(start -0.12065 -0.305054)
			(end -0.12065 -0.2794)
			(stroke
				(width 0.1)
				(type default)
			)
			(layer "F.Fab")
		)
		(fp_line
			(start -0.67945 0.3048)
			(end -0.67945 -0.305054)
			(stroke
				(width 0.1)
				(type default)
			)
			(layer "F.Fab")
		)
		(fp_line
			(start -0.67945 -0.305054)
			(end -0.12065 -0.305054)
			(stroke
				(width 0.1)
				(type default)
			)
			(layer "F.Fab")
		)
		(pad "1" smd circle
			(at -0.40005 0 180)
			(size 0 0)
			(layers "F.Cu" "F.Mask" "F.Paste")
			(net "CLK_25M_CK440_CPU0_DP")
		)
		(pad "2" smd circle
			(at 0.40005 0 180)
			(size 0 0)
			(layers "F.Cu" "F.Mask" "F.Paste")
			(net "CLK_25M_CK440_CPU0_R_DP")
		)
	)
	(footprint ""
		(layer "F.Cu")
		(at 349.014034 -69.13118)
		(property "Reference" "C148"
			(at 0 0 0)
			(layer "F.SilkS")
			(hide yes)
			(effects
				(font
					(size 1.27 1.27)
				)
			)
		)
		(property "Value" ""
			(at 0 0 0)
			(layer "F.Fab")
			(effects
				(font
					(size 1.27 1.27)
				)
			)
		)
		(duplicate_pad_numbers_are_jumpers no)
		(fp_line
			(start -0.299974 -0.150114)
			(end 0.299974 -0.150114)
			(stroke
				(width 0.1)
				(type default)
			)
			(layer "F.Fab")
		)
		(fp_line
			(start -0.299974 0.150114)
			(end -0.299974 -0.150114)
			(stroke
				(width 0.1)
				(type default)
			)
			(layer "F.Fab")
		)
		(fp_line
			(start 0.299974 -0.150114)
			(end 0.299974 0.150114)
			(stroke
				(width 0.1)
				(type default)
			)
			(layer "F.Fab")
		)
		(fp_line
			(start 0.299974 0.150114)
			(end -0.299974 0.150114)
			(stroke
				(width 0.1)
				(type default)
			)
			(layer "F.Fab")
		)
		(pad "1" smd rect
			(at -0.2667 0)
			(size 0.3048 0.381)
			(layers "F.Cu" "F.Mask" "F.Paste")
			(net "DMI_CPU0_PCH_TX_C_DP<3>")
		)
		(pad "2" smd rect
			(at 0.2667 0)
			(size 0.3048 0.381)
			(layers "F.Cu" "F.Mask" "F.Paste")
			(net "DMI_CPU0_PCH_TX_DP<3>")
		)
		(zone
			(layer "In1.Cu")
			(hatch none 0.5)
			(connect_pads
				(clearance 0)
			)
			(min_thickness 0.25)
			(keepout
				(tracks not_allowed)
				(vias allowed)
				(pads allowed)
				(copperpour not_allowed)
				(footprints allowed)
			)
			(placement
				(enabled no)
				(sheetname "")
			)
			(fill
				(thermal_gap 0.5)
				(thermal_bridge_width 0.5)
				(island_removal_mode 0)
			)
			(polygon
				(pts
					(arc
						(start 348.620334 -68.88988)
						(mid 348.566452 -68.912198)
						(end 348.544134 -68.96608)
					)
					(arc
						(start 348.544134 -69.29628)
						(mid 348.566452 -69.350162)
						(end 348.620334 -69.37248)
					)
					(arc
						(start 348.874334 -69.37248)
						(mid 348.928216 -69.350162)
						(end 348.950534 -69.29628)
					)
					(arc
						(start 348.950534 -68.96608)
						(mid 348.928216 -68.912198)
						(end 348.874334 -68.88988)
					)
				)
			)
		)
		(zone
			(layer "In1.Cu")
			(hatch none 0.5)
			(connect_pads
				(clearance 0)
			)
			(min_thickness 0.25)
			(keepout
				(tracks not_allowed)
				(vias allowed)
				(pads allowed)
				(copperpour not_allowed)
				(footprints allowed)
			)
			(placement
				(enabled no)
				(sheetname "")
			)
			(fill
				(thermal_gap 0.5)
				(thermal_bridge_width 0.5)
				(island_removal_mode 0)
			)
			(polygon
				(pts
					(arc
						(start 349.153734 -68.88988)
						(mid 349.099852 -68.912198)
						(end 349.077534 -68.96608)
					)
					(arc
						(start 349.077534 -69.29628)
						(mid 349.099852 -69.350162)
						(end 349.153734 -69.37248)
					)
					(arc
						(start 349.407734 -69.37248)
						(mid 349.461616 -69.350162)
						(end 349.483934 -69.29628)
					)
					(arc
						(start 349.483934 -68.96608)
						(mid 349.461616 -68.912198)
						(end 349.407734 -68.88988)
					)
				)
			)
		)
	)
)
